(kicad_pcb
	(version 20260206)
	(generator "pcbnew")
	(generator_version "10.0")
	(general
		(thickness 1.6)
		(legacy_teardrops no)
	)
	(paper "A4")
	(title_block
		(title "01162023_DA0F0TEBIF0_F0T_Expander_BD_F_brd_V02_OCP.brd")
		(comment 1 "Grand Teton / footprints 5729-5734 of 9728")
	)
	(layers
		(0 "F.Cu" signal "TOP")
		(4 "In1.Cu" signal "GND")
		(6 "In2.Cu" signal "VCC")
		(8 "In3.Cu" signal "VCC1")
		(10 "In4.Cu" signal "GND1")
		(12 "In5.Cu" signal "IN1")
		(14 "In6.Cu" signal "GND2")
		(16 "In7.Cu" signal "IN2")
		(18 "In8.Cu" signal "GND3")
		(20 "In9.Cu" signal "IN3")
		(22 "In10.Cu" signal "GND4")
		(24 "In11.Cu" signal "IN4")
		(26 "In12.Cu" signal "GND5")
		(28 "In13.Cu" signal "IN5")
		(30 "In14.Cu" signal "GND6")
		(32 "In15.Cu" signal "IN6")
		(34 "In16.Cu" signal "GND7")
		(2 "B.Cu" signal "BOTTOM")
		(9 "F.Adhes" user "F.Adhesive")
		(11 "B.Adhes" user "B.Adhesive")
		(13 "F.Paste" user "Package Geometry/Pastemask Top")
		(15 "B.Paste" user "Package Geometry/Pastemask Bottom")
		(5 "F.SilkS" user "Ref Des/Silkscreen Top")
		(7 "B.SilkS" user "Ref Des/Silkscreen Bottom")
		(1 "F.Mask" user "Board Geometry/Soldermask Top")
		(3 "B.Mask" user "Board Geometry/Soldermask Bottom")
		(17 "Dwgs.User" user "User.Drawings")
		(19 "Cmts.User" user "User.Comments")
		(21 "Eco1.User" user "User.Eco1")
		(23 "Eco2.User" user "User.Eco2")
		(25 "Edge.Cuts" user "Board Geometry/Outline")
		(27 "Margin" user)
		(31 "F.CrtYd" user "Package Geometry/Place Bound Top")
		(29 "B.CrtYd" user "Package Geometry/Place Bound Bottom")
		(35 "F.Fab" user "Ref Des/Assembly Top")
		(33 "B.Fab" user "Ref Des/Assembly Bottom")
	)
	(footprint ""
		(layer "F.Cu")
		(at 365.506 -198.755 180)
		(property "Reference" "R4688"
			(at 0 0 180)
			(layer "F.SilkS")
			(hide yes)
			(effects
				(font
					(size 1.27 1.27)
				)
			)
		)
		(property "Value" ""
			(at 0 0 180)
			(layer "F.Fab")
			(effects
				(font
					(size 1.27 1.27)
				)
			)
		)
		(duplicate_pad_numbers_are_jumpers no)
		(fp_line
			(start 0.7874 0.4064)
			(end -0.7874 0.4064)
			(stroke
				(width 0.1524)
				(type default)
			)
			(layer "F.SilkS")
		)
		(fp_line
			(start 0.7874 -0.4064)
			(end 0.7874 0.4064)
			(stroke
				(width 0.1524)
				(type default)
			)
			(layer "F.SilkS")
		)
		(fp_line
			(start -0.7874 0.4064)
			(end -0.7874 -0.4064)
			(stroke
				(width 0.1524)
				(type default)
			)
			(layer "F.SilkS")
		)
		(fp_line
			(start -0.7874 -0.4064)
			(end 0.7874 -0.4064)
			(stroke
				(width 0.1524)
				(type default)
			)
			(layer "F.SilkS")
		)
		(fp_line
			(start 0.67945 0.3048)
			(end 0.120396 0.3048)
			(stroke
				(width 0.1)
				(type default)
			)
			(layer "F.Fab")
		)
		(fp_line
			(start 0.67945 -0.3048)
			(end 0.67945 0.3048)
			(stroke
				(width 0.1)
				(type default)
			)
			(layer "F.Fab")
		)
		(fp_line
			(start 0.12065 -0.2794)
			(end 0.12065 -0.3048)
			(stroke
				(width 0.1)
				(type default)
			)
			(layer "F.Fab")
		)
		(fp_line
			(start 0.12065 -0.3048)
			(end 0.67945 -0.3048)
			(stroke
				(width 0.1)
				(type default)
			)
			(layer "F.Fab")
		)
		(fp_line
			(start 0.120396 0.3048)
			(end 0.120396 0.2794)
			(stroke
				(width 0.1)
				(type default)
			)
			(layer "F.Fab")
		)
		(fp_line
			(start 0.120396 0.2794)
			(end -0.12065 0.2794)
			(stroke
				(width 0.1)
				(type default)
			)
			(layer "F.Fab")
		)
		(fp_line
			(start -0.12065 0.3048)
			(end -0.67945 0.3048)
			(stroke
				(width 0.1)
				(type default)
			)
			(layer "F.Fab")
		)
		(fp_line
			(start -0.12065 0.2794)
			(end -0.12065 0.3048)
			(stroke
				(width 0.1)
				(type default)
			)
			(layer "F.Fab")
		)
		(fp_line
			(start -0.12065 -0.2794)
			(end 0.12065 -0.2794)
			(stroke
				(width 0.1)
				(type default)
			)
			(layer "F.Fab")
		)
		(fp_line
			(start -0.12065 -0.305054)
			(end -0.12065 -0.2794)
			(stroke
				(width 0.1)
				(type default)
			)
			(layer "F.Fab")
		)
		(fp_line
			(start -0.67945 0.3048)
			(end -0.67945 -0.305054)
			(stroke
				(width 0.1)
				(type default)
			)
			(layer "F.Fab")
		)
		(fp_line
			(start -0.67945 -0.305054)
			(end -0.12065 -0.305054)
			(stroke
				(width 0.1)
				(type default)
			)
			(layer "F.Fab")
		)
		(pad "1" smd circle
			(at -0.40005 0 180)
			(size 0 0)
			(layers "F.Cu" "F.Mask" "F.Paste")
			(net "RST_PEX_SSD4_PERST_N")
		)
		(pad "2" smd circle
			(at 0.40005 0 180)
			(size 0 0)
			(layers "F.Cu" "F.Mask" "F.Paste")
			(net "RST_PEX_SSD4_PERST_R_N")
		)
	)
	(footprint ""
		(layer "F.Cu")
		(at 246.137938 -308.095396 -90)
		(property "Reference" "PC980"
			(at 0 0 270)
			(layer "F.SilkS")
			(hide yes)
			(effects
				(font
					(size 1.27 1.27)
				)
			)
		)
		(property "Value" ""
			(at 0 0 270)
			(layer "F.Fab")
			(effects
				(font
					(size 1.27 1.27)
				)
			)
		)
		(duplicate_pad_numbers_are_jumpers no)
		(fp_line
			(start -0.7874 0.4064)
			(end -0.7874 -0.4064)
			(stroke
				(width 0.1524)
				(type default)
			)
			(layer "F.SilkS")
		)
		(fp_line
			(start 0.7874 0.4064)
			(end -0.7874 0.4064)
			(stroke
				(width 0.1524)
				(type default)
			)
			(layer "F.SilkS")
		)
		(fp_line
			(start -0.7874 -0.4064)
			(end 0.7874 -0.4064)
			(stroke
				(width 0.1524)
				(type default)
			)
			(layer "F.SilkS")
		)
		(fp_line
			(start 0.7874 -0.4064)
			(end 0.7874 0.4064)
			(stroke
				(width 0.1524)
				(type default)
			)
			(layer "F.SilkS")
		)
		(fp_line
			(start -0.67945 0.3048)
			(end -0.67945 -0.305054)
			(stroke
				(width 0.1)
				(type default)
			)
			(layer "F.Fab")
		)
		(fp_line
			(start -0.12065 0.3048)
			(end -0.67945 0.3048)
			(stroke
				(width 0.1)
				(type default)
			)
			(layer "F.Fab")
		)
		(fp_line
			(start 0.120396 0.3048)
			(end 0.120396 0.2794)
			(stroke
				(width 0.1)
				(type default)
			)
			(layer "F.Fab")
		)
		(fp_line
			(start 0.67945 0.3048)
			(end 0.120396 0.3048)
			(stroke
				(width 0.1)
				(type default)
			)
			(layer "F.Fab")
		)
		(fp_line
			(start -0.12065 0.2794)
			(end -0.12065 0.3048)
			(stroke
				(width 0.1)
				(type default)
			)
			(layer "F.Fab")
		)
		(fp_line
			(start 0.120396 0.2794)
			(end -0.12065 0.2794)
			(stroke
				(width 0.1)
				(type default)
			)
			(layer "F.Fab")
		)
		(fp_line
			(start -0.12065 -0.2794)
			(end 0.12065 -0.2794)
			(stroke
				(width 0.1)
				(type default)
			)
			(layer "F.Fab")
		)
		(fp_line
			(start 0.12065 -0.2794)
			(end 0.12065 -0.3048)
			(stroke
				(width 0.1)
				(type default)
			)
			(layer "F.Fab")
		)
		(fp_line
			(start 0.12065 -0.3048)
			(end 0.67945 -0.3048)
			(stroke
				(width 0.1)
				(type default)
			)
			(layer "F.Fab")
		)
		(fp_line
			(start 0.67945 -0.3048)
			(end 0.67945 0.3048)
			(stroke
				(width 0.1)
				(type default)
			)
			(layer "F.Fab")
		)
		(fp_line
			(start -0.67945 -0.305054)
			(end -0.12065 -0.305054)
			(stroke
				(width 0.1)
				(type default)
			)
			(layer "F.Fab")
		)
		(fp_line
			(start -0.12065 -0.305054)
			(end -0.12065 -0.2794)
			(stroke
				(width 0.1)
				(type default)
			)
			(layer "F.Fab")
		)
		(pad "1" smd circle
			(at -0.40005 0 270)
			(size 0 0)
			(layers "F.Cu" "F.Mask" "F.Paste")
			(net "SH_P1V25_PEX2_FB_P")
		)
		(pad "2" smd circle
			(at 0.40005 0 270)
			(size 0 0)
			(layers "F.Cu" "F.Mask" "F.Paste")
			(net "SH_P1V25_PEX2_FB_N")
		)
	)
	(footprint ""
		(layer "F.Cu")
		(at 9.195054 -59.577986 90)
		(property "Reference" "PC506"
			(at 0 0 90)
			(layer "F.SilkS")
			(hide yes)
			(effects
				(font
					(size 1.27 1.27)
				)
			)
		)
		(property "Value" ""
			(at 0 0 90)
			(layer "F.Fab")
			(effects
				(font
					(size 1.27 1.27)
				)
			)
		)
		(duplicate_pad_numbers_are_jumpers no)
		(fp_line
			(start 0.7874 -0.4064)
			(end 0.7874 0.4064)
			(stroke
				(width 0.1524)
				(type default)
			)
			(layer "F.SilkS")
		)
		(fp_line
			(start -0.7874 -0.4064)
			(end 0.7874 -0.4064)
			(stroke
				(width 0.1524)
				(type default)
			)
			(layer "F.SilkS")
		)
		(fp_line
			(start 0.7874 0.4064)
			(end -0.7874 0.4064)
			(stroke
				(width 0.1524)
				(type default)
			)
			(layer "F.SilkS")
		)
		(fp_line
			(start -0.7874 0.4064)
			(end -0.7874 -0.4064)
			(stroke
				(width 0.1524)
				(type default)
			)
			(layer "F.SilkS")
		)
		(fp_line
			(start -0.12065 -0.305054)
			(end -0.12065 -0.2794)
			(stroke
				(width 0.1)
				(type default)
			)
			(layer "F.Fab")
		)
		(fp_line
			(start -0.67945 -0.305054)
			(end -0.12065 -0.305054)
			(stroke
				(width 0.1)
				(type default)
			)
			(layer "F.Fab")
		)
		(fp_line
			(start 0.67945 -0.3048)
			(end 0.67945 0.3048)
			(stroke
				(width 0.1)
				(type default)
			)
			(layer "F.Fab")
		)
		(fp_line
			(start 0.12065 -0.3048)
			(end 0.67945 -0.3048)
			(stroke
				(width 0.1)
				(type default)
			)
			(layer "F.Fab")
		)
		(fp_line
			(start 0.12065 -0.2794)
			(end 0.12065 -0.3048)
			(stroke
				(width 0.1)
				(type default)
			)
			(layer "F.Fab")
		)
		(fp_line
			(start -0.12065 -0.2794)
			(end 0.12065 -0.2794)
			(stroke
				(width 0.1)
				(type default)
			)
			(layer "F.Fab")
		)
		(fp_line
			(start 0.120396 0.2794)
			(end -0.12065 0.2794)
			(stroke
				(width 0.1)
				(type default)
			)
			(layer "F.Fab")
		)
		(fp_line
			(start -0.12065 0.2794)
			(end -0.12065 0.3048)
			(stroke
				(width 0.1)
				(type default)
			)
			(layer "F.Fab")
		)
		(fp_line
			(start 0.67945 0.3048)
			(end 0.120396 0.3048)
			(stroke
				(width 0.1)
				(type default)
			)
			(layer "F.Fab")
		)
		(fp_line
			(start 0.120396 0.3048)
			(end 0.120396 0.2794)
			(stroke
				(width 0.1)
				(type default)
			)
			(layer "F.Fab")
		)
		(fp_line
			(start -0.12065 0.3048)
			(end -0.67945 0.3048)
			(stroke
				(width 0.1)
				(type default)
			)
			(layer "F.Fab")
		)
		(fp_line
			(start -0.67945 0.3048)
			(end -0.67945 -0.305054)
			(stroke
				(width 0.1)
				(type default)
			)
			(layer "F.Fab")
		)
		(pad "1" smd circle
			(at -0.40005 0 90)
			(size 0 0)
			(layers "F.Cu" "F.Mask" "F.Paste")
			(net "P3V3_SSD0_SS")
		)
		(pad "2" smd circle
			(at 0.40005 0 90)
			(size 0 0)
			(layers "F.Cu" "F.Mask" "F.Paste")
			(net "GND")
		)
	)
	(footprint ""
		(layer "F.Cu")
		(at 222.5548 -22.961346 90)
		(property "Reference" "R1676"
			(at 0 0 90)
			(layer "F.SilkS")
			(hide yes)
			(effects
				(font
					(size 1.27 1.27)
				)
			)
		)
		(property "Value" ""
			(at 0 0 90)
			(layer "F.Fab")
			(effects
				(font
					(size 1.27 1.27)
				)
			)
		)
		(duplicate_pad_numbers_are_jumpers no)
		(fp_line
			(start 0.7874 -0.4064)
			(end 0.7874 0.4064)
			(stroke
				(width 0.1524)
				(type default)
			)
			(layer "F.SilkS")
		)
		(fp_line
			(start -0.7874 -0.4064)
			(end 0.7874 -0.4064)
			(stroke
				(width 0.1524)
				(type default)
			)
			(layer "F.SilkS")
		)
		(fp_line
			(start 0.7874 0.4064)
			(end -0.7874 0.4064)
			(stroke
				(width 0.1524)
				(type default)
			)
			(layer "F.SilkS")
		)
		(fp_line
			(start -0.7874 0.4064)
			(end -0.7874 -0.4064)
			(stroke
				(width 0.1524)
				(type default)
			)
			(layer "F.SilkS")
		)
		(fp_line
			(start -0.12065 -0.305054)
			(end -0.12065 -0.2794)
			(stroke
				(width 0.1)
				(type default)
			)
			(layer "F.Fab")
		)
		(fp_line
			(start -0.67945 -0.305054)
			(end -0.12065 -0.305054)
			(stroke
				(width 0.1)
				(type default)
			)
			(layer "F.Fab")
		)
		(fp_line
			(start 0.67945 -0.3048)
			(end 0.67945 0.3048)
			(stroke
				(width 0.1)
				(type default)
			)
			(layer "F.Fab")
		)
		(fp_line
			(start 0.12065 -0.3048)
			(end 0.67945 -0.3048)
			(stroke
				(width 0.1)
				(type default)
			)
			(layer "F.Fab")
		)
		(fp_line
			(start 0.12065 -0.2794)
			(end 0.12065 -0.3048)
			(stroke
				(width 0.1)
				(type default)
			)
			(layer "F.Fab")
		)
		(fp_line
			(start -0.12065 -0.2794)
			(end 0.12065 -0.2794)
			(stroke
				(width 0.1)
				(type default)
			)
			(layer "F.Fab")
		)
		(fp_line
			(start 0.120396 0.2794)
			(end -0.12065 0.2794)
			(stroke
				(width 0.1)
				(type default)
			)
			(layer "F.Fab")
		)
		(fp_line
			(start -0.12065 0.2794)
			(end -0.12065 0.3048)
			(stroke
				(width 0.1)
				(type default)
			)
			(layer "F.Fab")
		)
		(fp_line
			(start 0.67945 0.3048)
			(end 0.120396 0.3048)
			(stroke
				(width 0.1)
				(type default)
			)
			(layer "F.Fab")
		)
		(fp_line
			(start 0.120396 0.3048)
			(end 0.120396 0.2794)
			(stroke
				(width 0.1)
				(type default)
			)
			(layer "F.Fab")
		)
		(fp_line
			(start -0.12065 0.3048)
			(end -0.67945 0.3048)
			(stroke
				(width 0.1)
				(type default)
			)
			(layer "F.Fab")
		)
		(fp_line
			(start -0.67945 0.3048)
			(end -0.67945 -0.305054)
			(stroke
				(width 0.1)
				(type default)
			)
			(layer "F.Fab")
		)
		(pad "1" smd circle
			(at -0.40005 0 90)
			(size 0 0)
			(layers "F.Cu" "F.Mask" "F.Paste")
			(net "SMB_SSD7_ISO_EN")
		)
		(pad "2" smd circle
			(at 0.40005 0 90)
			(size 0 0)
			(layers "F.Cu" "F.Mask" "F.Paste")
			(net "P3V3_AUX")
		)
	)
	(footprint ""
		(layer "F.Cu")
		(at 378.852684 -87.6808)
		(property "Reference" "R1767"
			(at 0 0 0)
			(layer "F.SilkS")
			(hide yes)
			(effects
				(font
					(size 1.27 1.27)
				)
			)
		)
		(property "Value" ""
			(at 0 0 0)
			(layer "F.Fab")
			(effects
				(font
					(size 1.27 1.27)
				)
			)
		)
		(duplicate_pad_numbers_are_jumpers no)
		(fp_line
			(start -0.7874 -0.4064)
			(end 0.7874 -0.4064)
			(stroke
				(width 0.1524)
				(type default)
			)
			(layer "F.SilkS")
		)
		(fp_line
			(start -0.7874 0.4064)
			(end -0.7874 -0.4064)
			(stroke
				(width 0.1524)
				(type default)
			)
			(layer "F.SilkS")
		)
		(fp_line
			(start 0.7874 -0.4064)
			(end 0.7874 0.4064)
			(stroke
				(width 0.1524)
				(type default)
			)
			(layer "F.SilkS")
		)
		(fp_line
			(start 0.7874 0.4064)
			(end -0.7874 0.4064)
			(stroke
				(width 0.1524)
				(type default)
			)
			(layer "F.SilkS")
		)
		(fp_line
			(start -0.67945 -0.305054)
			(end -0.12065 -0.305054)
			(stroke
				(width 0.1)
				(type default)
			)
			(layer "F.Fab")
		)
		(fp_line
			(start -0.67945 0.3048)
			(end -0.67945 -0.305054)
			(stroke
				(width 0.1)
				(type default)
			)
			(layer "F.Fab")
		)
		(fp_line
			(start -0.12065 -0.305054)
			(end -0.12065 -0.2794)
			(stroke
				(width 0.1)
				(type default)
			)
			(layer "F.Fab")
		)
		(fp_line
			(start -0.12065 -0.2794)
			(end 0.12065 -0.2794)
			(stroke
				(width 0.1)
				(type default)
			)
			(layer "F.Fab")
		)
		(fp_line
			(start -0.12065 0.2794)
			(end -0.12065 0.3048)
			(stroke
				(width 0.1)
				(type default)
			)
			(layer "F.Fab")
		)
		(fp_line
			(start -0.12065 0.3048)
			(end -0.67945 0.3048)
			(stroke
				(width 0.1)
				(type default)
			)
			(layer "F.Fab")
		)
		(fp_line
			(start 0.120396 0.2794)
			(end -0.12065 0.2794)
			(stroke
				(width 0.1)
				(type default)
			)
			(layer "F.Fab")
		)
		(fp_line
			(start 0.120396 0.3048)
			(end 0.120396 0.2794)
			(stroke
				(width 0.1)
				(type default)
			)
			(layer "F.Fab")
		)
		(fp_line
			(start 0.12065 -0.3048)
			(end 0.67945 -0.3048)
			(stroke
				(width 0.1)
				(type default)
			)
			(layer "F.Fab")
		)
		(fp_line
			(start 0.12065 -0.2794)
			(end 0.12065 -0.3048)
			(stroke
				(width 0.1)
				(type default)
			)
			(layer "F.Fab")
		)
		(fp_line
			(start 0.67945 -0.3048)
			(end 0.67945 0.3048)
			(stroke
				(width 0.1)
				(type default)
			)
			(layer "F.Fab")
		)
		(fp_line
			(start 0.67945 0.3048)
			(end 0.120396 0.3048)
			(stroke
				(width 0.1)
				(type default)
			)
			(layer "F.Fab")
		)
		(pad "1" smd circle
			(at -0.40005 0)
			(size 0 0)
			(layers "F.Cu" "F.Mask" "F.Paste")
			(net "SMB_BIC_I2C6_MUX_NIC_ADC_R_SCL")
		)
		(pad "2" smd circle
			(at 0.40005 0)
			(size 0 0)
			(layers "F.Cu" "F.Mask" "F.Paste")
			(net "SMB_BIC_I2C6_MUX_NIC_ADC_SCL")
		)
	)
	(footprint ""
		(layer "F.Cu")
		(at 341.63 -205.232 -90)
		(property "Reference" "R4137"
			(at 0 0 270)
			(layer "F.SilkS")
			(hide yes)
			(effects
				(font
					(size 1.27 1.27)
				)
			)
		)
		(property "Value" ""
			(at 0 0 270)
			(layer "F.Fab")
			(effects
				(font
					(size 1.27 1.27)
				)
			)
		)
		(duplicate_pad_numbers_are_jumpers no)
		(fp_line
			(start -0.7874 0.4064)
			(end -0.7874 -0.4064)
			(stroke
				(width 0.1524)
				(type default)
			)
			(layer "F.SilkS")
		)
		(fp_line
			(start 0.7874 0.4064)
			(end -0.7874 0.4064)
			(stroke
				(width 0.1524)
				(type default)
			)
			(layer "F.SilkS")
		)
		(fp_line
			(start -0.7874 -0.4064)
			(end 0.7874 -0.4064)
			(stroke
				(width 0.1524)
				(type default)
			)
			(layer "F.SilkS")
		)
		(fp_line
			(start 0.7874 -0.4064)
			(end 0.7874 0.4064)
			(stroke
				(width 0.1524)
				(type default)
			)
			(layer "F.SilkS")
		)
		(fp_line
			(start -0.67945 0.3048)
			(end -0.67945 -0.305054)
			(stroke
				(width 0.1)
				(type default)
			)
			(layer "F.Fab")
		)
		(fp_line
			(start -0.12065 0.3048)
			(end -0.67945 0.3048)
			(stroke
				(width 0.1)
				(type default)
			)
			(layer "F.Fab")
		)
		(fp_line
			(start 0.120396 0.3048)
			(end 0.120396 0.2794)
			(stroke
				(width 0.1)
				(type default)
			)
			(layer "F.Fab")
		)
		(fp_line
			(start 0.67945 0.3048)
			(end 0.120396 0.3048)
			(stroke
				(width 0.1)
				(type default)
			)
			(layer "F.Fab")
		)
		(fp_line
			(start -0.12065 0.2794)
			(end -0.12065 0.3048)
			(stroke
				(width 0.1)
				(type default)
			)
			(layer "F.Fab")
		)
		(fp_line
			(start 0.120396 0.2794)
			(end -0.12065 0.2794)
			(stroke
				(width 0.1)
				(type default)
			)
			(layer "F.Fab")
		)
		(fp_line
			(start -0.12065 -0.2794)
			(end 0.12065 -0.2794)
			(stroke
				(width 0.1)
				(type default)
			)
			(layer "F.Fab")
		)
		(fp_line
			(start 0.12065 -0.2794)
			(end 0.12065 -0.3048)
			(stroke
				(width 0.1)
				(type default)
			)
			(layer "F.Fab")
		)
		(fp_line
			(start 0.12065 -0.3048)
			(end 0.67945 -0.3048)
			(stroke
				(width 0.1)
				(type default)
			)
			(layer "F.Fab")
		)
		(fp_line
			(start 0.67945 -0.3048)
			(end 0.67945 0.3048)
			(stroke
				(width 0.1)
				(type default)
			)
			(layer "F.Fab")
		)
		(fp_line
			(start -0.67945 -0.305054)
			(end -0.12065 -0.305054)
			(stroke
				(width 0.1)
				(type default)
			)
			(layer "F.Fab")
		)
		(fp_line
			(start -0.12065 -0.305054)
			(end -0.12065 -0.2794)
			(stroke
				(width 0.1)
				(type default)
			)
			(layer "F.Fab")
		)
		(pad "1" smd circle
			(at -0.40005 0 270)
			(size 0 0)
			(layers "F.Cu" "F.Mask" "F.Paste")
			(net "RST_SSD13_PERST_N")
		)
		(pad "2" smd circle
			(at 0.40005 0 270)
			(size 0 0)
			(layers "F.Cu" "F.Mask" "F.Paste")
			(net "RST_SSD13_PERST_R_N")
		)
	)
)
